# T6G (Grand Teton) — schematic netlist excerpt (pin names and nets, part order shuffled) for the footprints in the layout excerpt that follows; sources: Cadence DE-HDL packaged netlist, KiCad conversion of 04192023_DAF0TMB3IC0_F0TG_MB_C_brd_V02_OCP.brd

R303  Q_RES  1K 1% CHIP  pkg 0402LF  page 98 : A = PWRGD_CHA_CPU1_DIMM0 ; B = PWRGD_CHAF_CPU1
PC483_1  Q_CAP  22UF 16V 20% X6S  pkg C0805  page 194 : A = SW_P12V_AUX_PVDDCR_CPU0_P0_FLT ; B = GND
C481  Q_CAP  0.1UF 10V 10% X7S  pkg C0201  page 356 : A = P0V9_CPU1_RT3_2A ; B = GND
PC443_2  Q_CAP  22UF 16V 20% X6S  pkg C0805  page 222 : A = SW_P12V_AUX_PVDDIO_P1_FLT ; B = GND

(kicad_pcb
	(version 20260206)
	(generator "pcbnew")
	(generator_version "10.0")
	(general
		(thickness 1.6)
		(legacy_teardrops no)
	)
	(paper "A4")
	(title_block
		(title "04192023_DAF0TMB3IC0_F0TG_MB_C_brd_V02_OCP.brd")
		(comment 1 "Grand Teton / footprints 6437-6440 of 8354")
	)
	(layers
		(0 "F.Cu" signal "TOP")
		(4 "In1.Cu" signal "GND")
		(6 "In2.Cu" signal "IN1")
		(8 "In3.Cu" signal "GND1")
		(10 "In4.Cu" signal "IN2")
		(12 "In5.Cu" signal "GND2")
		(14 "In6.Cu" signal "IN3")
		(16 "In7.Cu" signal "GND3")
		(18 "In8.Cu" signal "VCC")
		(20 "In9.Cu" signal "VCC1")
		(22 "In10.Cu" signal "GND4")
		(24 "In11.Cu" signal "IN4")
		(26 "In12.Cu" signal "GND5")
		(28 "In13.Cu" signal "IN5")
		(30 "In14.Cu" signal "GND6")
		(32 "In15.Cu" signal "IN6")
		(34 "In16.Cu" signal "GND7")
		(2 "B.Cu" signal "BOTTOM")
		(9 "F.Adhes" user "F.Adhesive")
		(11 "B.Adhes" user "B.Adhesive")
		(13 "F.Paste" user "Package Geometry/Pastemask Top")
		(15 "B.Paste" user "Package Geometry/Pastemask Bottom")
		(5 "F.SilkS" user "Ref Des/Silkscreen Top")
		(7 "B.SilkS" user "Ref Des/Silkscreen Bottom")
		(1 "F.Mask" user "Board Geometry/Soldermask Top")
		(3 "B.Mask" user "Board Geometry/Soldermask Bottom")
		(17 "Dwgs.User" user "User.Drawings")
		(19 "Cmts.User" user "User.Comments")
		(21 "Eco1.User" user "User.Eco1")
		(23 "Eco2.User" user "User.Eco2")
		(25 "Edge.Cuts" user "Board Geometry/Outline")
		(27 "Margin" user)
		(31 "F.CrtYd" user "Package Geometry/Place Bound Top")
		(29 "B.CrtYd" user "Package Geometry/Place Bound Bottom")
		(35 "F.Fab" user "Ref Des/Assembly Top")
		(33 "B.Fab" user "Ref Des/Assembly Bottom")
	)
	(footprint ""
		(layer "B.Cu")
		(at 52.364386 -190.821564)
		(property "Reference" "R303"
			(at 0 0 0)
			(layer "B.SilkS")
			(hide yes)
			(effects
				(font
					(size 1.27 1.27)
				)
				(justify mirror)
			)
		)
		(property "Value" ""
			(at 0 0 0)
			(layer "B.Fab")
			(effects
				(font
					(size 1.27 1.27)
				)
				(justify mirror)
			)
		)
		(duplicate_pad_numbers_are_jumpers no)
		(fp_line
			(start -0.7874 -0.4064)
			(end -0.7874 0.4064)
			(stroke
				(width 0.1524)
				(type default)
			)
			(layer "B.SilkS")
		)
		(fp_line
			(start -0.7874 0.4064)
			(end 0.7874 0.4064)
			(stroke
				(width 0.1524)
				(type default)
			)
			(layer "B.SilkS")
		)
		(fp_line
			(start 0.7874 -0.4064)
			(end -0.7874 -0.4064)
			(stroke
				(width 0.1524)
				(type default)
			)
			(layer "B.SilkS")
		)
		(fp_line
			(start 0.7874 0.4064)
			(end 0.7874 -0.4064)
			(stroke
				(width 0.1524)
				(type default)
			)
			(layer "B.SilkS")
		)
		(fp_line
			(start -0.67945 -0.3048)
			(end -0.67945 0.3048)
			(stroke
				(width 0.1)
				(type default)
			)
			(layer "B.Fab")
		)
		(fp_line
			(start -0.67945 0.3048)
			(end -0.120396 0.3048)
			(stroke
				(width 0.1)
				(type default)
			)
			(layer "B.Fab")
		)
		(fp_line
			(start -0.12065 -0.3048)
			(end -0.67945 -0.3048)
			(stroke
				(width 0.1)
				(type default)
			)
			(layer "B.Fab")
		)
		(fp_line
			(start -0.12065 -0.2794)
			(end -0.12065 -0.3048)
			(stroke
				(width 0.1)
				(type default)
			)
			(layer "B.Fab")
		)
		(fp_line
			(start -0.120396 0.2794)
			(end 0.12065 0.2794)
			(stroke
				(width 0.1)
				(type default)
			)
			(layer "B.Fab")
		)
		(fp_line
			(start -0.120396 0.3048)
			(end -0.120396 0.2794)
			(stroke
				(width 0.1)
				(type default)
			)
			(layer "B.Fab")
		)
		(fp_line
			(start 0.12065 -0.305054)
			(end 0.12065 -0.2794)
			(stroke
				(width 0.1)
				(type default)
			)
			(layer "B.Fab")
		)
		(fp_line
			(start 0.12065 -0.2794)
			(end -0.12065 -0.2794)
			(stroke
				(width 0.1)
				(type default)
			)
			(layer "B.Fab")
		)
		(fp_line
			(start 0.12065 0.2794)
			(end 0.12065 0.3048)
			(stroke
				(width 0.1)
				(type default)
			)
			(layer "B.Fab")
		)
		(fp_line
			(start 0.12065 0.3048)
			(end 0.67945 0.3048)
			(stroke
				(width 0.1)
				(type default)
			)
			(layer "B.Fab")
		)
		(fp_line
			(start 0.67945 -0.305054)
			(end 0.12065 -0.305054)
			(stroke
				(width 0.1)
				(type default)
			)
			(layer "B.Fab")
		)
		(fp_line
			(start 0.67945 0.3048)
			(end 0.67945 -0.305054)
			(stroke
				(width 0.1)
				(type default)
			)
			(layer "B.Fab")
		)
		(pad "1" smd circle
			(at 0.40005 0 180)
			(size 0 0)
			(layers "B.Cu" "B.Mask" "B.Paste")
			(net "PWRGD_CHA_CPU1_DIMM0")
		)
		(pad "2" smd circle
			(at -0.40005 0 180)
			(size 0 0)
			(layers "B.Cu" "B.Mask" "B.Paste")
			(net "PWRGD_CHAF_CPU1")
		)
	)
	(footprint ""
		(layer "B.Cu")
		(at 363.088936 -174.01794 90)
		(property "Reference" "PC483_1"
			(at 0 0 90)
			(layer "B.SilkS")
			(hide yes)
			(effects
				(font
					(size 1.27 1.27)
				)
				(justify mirror)
			)
		)
		(property "Value" ""
			(at 0 0 90)
			(layer "B.Fab")
			(effects
				(font
					(size 1.27 1.27)
				)
				(justify mirror)
			)
		)
		(duplicate_pad_numbers_are_jumpers no)
		(fp_line
			(start 1.524 -0.762)
			(end -1.524 -0.762)
			(stroke
				(width 0.1524)
				(type default)
			)
			(layer "B.SilkS")
		)
		(fp_line
			(start -1.524 -0.762)
			(end -1.524 0.762)
			(stroke
				(width 0.1524)
				(type default)
			)
			(layer "B.SilkS")
		)
		(fp_line
			(start 1.524 0.762)
			(end 1.524 -0.762)
			(stroke
				(width 0.1524)
				(type default)
			)
			(layer "B.SilkS")
		)
		(fp_line
			(start -1.524 0.762)
			(end 1.524 0.762)
			(stroke
				(width 0.1524)
				(type default)
			)
			(layer "B.SilkS")
		)
		(fp_line
			(start 1.1049 -0.724916)
			(end 1.1049 0.724916)
			(stroke
				(width 0.1)
				(type default)
			)
			(layer "B.Fab")
		)
		(fp_line
			(start -1.1049 -0.724916)
			(end 1.1049 -0.724916)
			(stroke
				(width 0.1)
				(type default)
			)
			(layer "B.Fab")
		)
		(fp_line
			(start 1.1049 0.724916)
			(end -1.1049 0.724916)
			(stroke
				(width 0.1)
				(type default)
			)
			(layer "B.Fab")
		)
		(fp_line
			(start -1.1049 0.724916)
			(end -1.1049 -0.724916)
			(stroke
				(width 0.1)
				(type default)
			)
			(layer "B.Fab")
		)
		(pad "1" smd rect
			(at 0.889 0 90)
			(size 1.016 1.27)
			(layers "B.Cu" "B.Mask" "B.Paste")
			(net "SW_P12V_AUX_PVDDCR_CPU0_P0_FLT")
		)
		(pad "2" smd rect
			(at -0.889 0 90)
			(size 1.016 1.27)
			(layers "B.Cu" "B.Mask" "B.Paste")
			(net "GND")
		)
	)
	(footprint ""
		(layer "B.Cu")
		(at 134.517384 -387.768592 180)
		(property "Reference" "C481"
			(at 0 0 0)
			(layer "B.SilkS")
			(hide yes)
			(effects
				(font
					(size 1.27 1.27)
				)
				(justify mirror)
			)
		)
		(property "Value" ""
			(at 0 0 0)
			(layer "B.Fab")
			(effects
				(font
					(size 1.27 1.27)
				)
				(justify mirror)
			)
		)
		(duplicate_pad_numbers_are_jumpers no)
		(fp_line
			(start 0.299974 0.150114)
			(end 0.299974 -0.150114)
			(stroke
				(width 0.1)
				(type default)
			)
			(layer "B.Fab")
		)
		(fp_line
			(start 0.299974 -0.150114)
			(end -0.299974 -0.150114)
			(stroke
				(width 0.1)
				(type default)
			)
			(layer "B.Fab")
		)
		(fp_line
			(start -0.299974 0.150114)
			(end 0.299974 0.150114)
			(stroke
				(width 0.1)
				(type default)
			)
			(layer "B.Fab")
		)
		(fp_line
			(start -0.299974 -0.150114)
			(end -0.299974 0.150114)
			(stroke
				(width 0.1)
				(type default)
			)
			(layer "B.Fab")
		)
		(pad "1" smd rect
			(at 0.2667 0)
			(size 0.3048 0.381)
			(layers "B.Cu" "B.Mask" "B.Paste")
			(net "P0V9_CPU1_RT3_2A")
		)
		(pad "2" smd rect
			(at -0.2667 0)
			(size 0.3048 0.381)
			(layers "B.Cu" "B.Mask" "B.Paste")
			(net "GND")
		)
	)
	(footprint ""
		(layer "B.Cu")
		(at 46.308518 -346.788994 90)
		(property "Reference" "PC443_2"
			(at 0 0 90)
			(layer "B.SilkS")
			(hide yes)
			(effects
				(font
					(size 1.27 1.27)
				)
				(justify mirror)
			)
		)
		(property "Value" ""
			(at 0 0 90)
			(layer "B.Fab")
			(effects
				(font
					(size 1.27 1.27)
				)
				(justify mirror)
			)
		)
		(duplicate_pad_numbers_are_jumpers no)
		(fp_line
			(start 1.524 -0.762)
			(end -1.524 -0.762)
			(stroke
				(width 0.1524)
				(type default)
			)
			(layer "B.SilkS")
		)
		(fp_line
			(start -1.524 -0.762)
			(end -1.524 0.762)
			(stroke
				(width 0.1524)
				(type default)
			)
			(layer "B.SilkS")
		)
		(fp_line
			(start 1.524 0.762)
			(end 1.524 -0.762)
			(stroke
				(width 0.1524)
				(type default)
			)
			(layer "B.SilkS")
		)
		(fp_line
			(start -1.524 0.762)
			(end 1.524 0.762)
			(stroke
				(width 0.1524)
				(type default)
			)
			(layer "B.SilkS")
		)
		(fp_line
			(start 1.1049 -0.724916)
			(end 1.1049 0.724916)
			(stroke
				(width 0.1)
				(type default)
			)
			(layer "B.Fab")
		)
		(fp_line
			(start -1.1049 -0.724916)
			(end 1.1049 -0.724916)
			(stroke
				(width 0.1)
				(type default)
			)
			(layer "B.Fab")
		)
		(fp_line
			(start 1.1049 0.724916)
			(end -1.1049 0.724916)
			(stroke
				(width 0.1)
				(type default)
			)
			(layer "B.Fab")
		)
		(fp_line
			(start -1.1049 0.724916)
			(end -1.1049 -0.724916)
			(stroke
				(width 0.1)
				(type default)
			)
			(layer "B.Fab")
		)
		(pad "1" smd rect
			(at 0.889 0 90)
			(size 1.016 1.27)
			(layers "B.Cu" "B.Mask" "B.Paste")
			(net "SW_P12V_AUX_PVDDIO_P1_FLT")
		)
		(pad "2" smd rect
			(at -0.889 0 90)
			(size 1.016 1.27)
			(layers "B.Cu" "B.Mask" "B.Paste")
			(net "GND")
		)
	)
)
